# S9S_MB_2U (Grand Teton) — schematic netlist excerpt (pin names and nets, part order shuffled) for the footprints in the layout excerpt that follows; sources: Cadence DE-HDL packaged netlist, KiCad conversion of 03242023_DA0F0TMBIJ0_F0T_Motherboard_J_brd_V01_OCP.brd

PU201  MAX15090BEWIT  MAX15090BEWI+T EMPTY  pkg BGA28_0-5_3-525X2-065  page 162
  ISENSE  = P12V_OCP_SENSE_2
  VCC  = P12V_OCP_VCC_2
  IN_A3  = P12V_AUX
  OUT_A4  = P12V_OCP_V3_2
  IN_A5  = P12V_AUX
  GATE  = P12V_OCP_GATE_2
  CDLY  = GND
  CB  = P12V_OCP_CB_2
  GND_B2  = GND
  IN_B3  = P12V_AUX
  OUT_B4  = P12V_OCP_V3_2
  IN_B5  = P12V_AUX
  OUT_B6  = P12V_OCP_V3_2
  \en#\  = GND
  GND_C1  = GND
  GND_C2  = GND
  IN_C3  = P12V_AUX
  OUT_C4  = P12V_OCP_V3_2
  IN_C5  = P12V_AUX
  OUT_C6  = P12V_OCP_V3_2
  \fault#\  = P12V_OCP_FAULT_2
  REG  = P12V_OCP_REG_2
  UV  = P12V_OCP_UV_2
  OV  = P12V_OCP_OV_2
  OUT_D4  = P12V_OCP_V3_2
  IN_D5  = P12V_AUX
  OUT_D6  = P12V_OCP_V3_2
  PG  = P12V_OCP_PWRGD_2

(kicad_pcb
	(version 20260206)
	(generator "pcbnew")
	(generator_version "10.0")
	(general
		(thickness 1.6)
		(legacy_teardrops no)
	)
	(paper "A4")
	(title_block
		(title "03242023_DA0F0TMBIJ0_F0T_Motherboard_J_brd_V01_OCP.brd")
		(comment 1 "Grand Teton / footprints 3211-3211 of 6105")
	)
	(layers
		(0 "F.Cu" signal "TOP")
		(4 "In1.Cu" signal "GND")
		(6 "In2.Cu" signal "IN1")
		(8 "In3.Cu" signal "GND1")
		(10 "In4.Cu" signal "IN2")
		(12 "In5.Cu" signal "GND2")
		(14 "In6.Cu" signal "IN3")
		(16 "In7.Cu" signal "GND3")
		(18 "In8.Cu" signal "VCC")
		(20 "In9.Cu" signal "VCC1")
		(22 "In10.Cu" signal "GND4")
		(24 "In11.Cu" signal "IN4")
		(26 "In12.Cu" signal "GND5")
		(28 "In13.Cu" signal "IN5")
		(30 "In14.Cu" signal "GND6")
		(32 "In15.Cu" signal "IN6")
		(34 "In16.Cu" signal "GND7")
		(2 "B.Cu" signal "BOTTOM")
		(9 "F.Adhes" user "F.Adhesive")
		(11 "B.Adhes" user "B.Adhesive")
		(13 "F.Paste" user "Package Geometry/Pastemask Top")
		(15 "B.Paste" user "Package Geometry/Pastemask Bottom")
		(5 "F.SilkS" user "Ref Des/Silkscreen Top")
		(7 "B.SilkS" user "Ref Des/Silkscreen Bottom")
		(1 "F.Mask" user "Board Geometry/Soldermask Top")
		(3 "B.Mask" user "Board Geometry/Soldermask Bottom")
		(17 "Dwgs.User" user "User.Drawings")
		(19 "Cmts.User" user "User.Comments")
		(21 "Eco1.User" user "User.Eco1")
		(23 "Eco2.User" user "User.Eco2")
		(25 "Edge.Cuts" user "Board Geometry/Outline")
		(27 "Margin" user)
		(31 "F.CrtYd" user "Package Geometry/Place Bound Top")
		(29 "B.CrtYd" user "Package Geometry/Place Bound Bottom")
		(35 "F.Fab" user "Ref Des/Assembly Top")
		(33 "B.Fab" user "Ref Des/Assembly Bottom")
	)
	(footprint ""
		(layer "F.Cu")
		(at 79.356458 -20.694142)
		(property "Reference" "PU201"
			(at -9.250172 -0.290322 0)
			(unlocked yes)
			(layer "F.SilkS")
			(effects
				(font
					(size 0.7874 0.5842)
					(thickness 0.1524)
				)
				(justify left)
			)
		)
		(property "Value" ""
			(at 0 0 0)
			(layer "F.Fab")
			(effects
				(font
					(size 1.27 1.27)
				)
			)
		)
		(duplicate_pad_numbers_are_jumpers no)
		(fp_line
			(start -1.774952 -1.039876)
			(end -1.774952 1.039876)
			(stroke
				(width 0.1524)
				(type default)
			)
			(layer "F.SilkS")
		)
		(fp_line
			(start -1.774952 1.039876)
			(end 1.774952 1.039876)
			(stroke
				(width 0.1524)
				(type default)
			)
			(layer "F.SilkS")
		)
		(fp_line
			(start 1.774952 -1.039876)
			(end -1.774952 -1.039876)
			(stroke
				(width 0.1524)
				(type default)
			)
			(layer "F.SilkS")
		)
		(fp_line
			(start 1.774952 1.039876)
			(end 1.774952 -1.039876)
			(stroke
				(width 0.1524)
				(type default)
			)
			(layer "F.SilkS")
		)
		(fp_poly
			(pts
				(xy -1.769872 -1.039876) (xy -1.769872 -0.249936) (xy -2.531872 -0.249936) (xy -2.531872 -1.801876)
				(xy -0.999998 -1.801876) (xy -0.999998 -1.039876)
			)
			(stroke
				(width 0)
				(type default)
			)
			(fill yes)
			(layer "F.SilkS")
		)
		(fp_line
			(start -1.769872 -1.039876)
			(end -1.769872 1.039876)
			(stroke
				(width 0.1)
				(type default)
			)
			(layer "F.Fab")
		)
		(fp_line
			(start -1.769872 1.039876)
			(end 1.769872 1.039876)
			(stroke
				(width 0.1)
				(type default)
			)
			(layer "F.Fab")
		)
		(fp_line
			(start 1.769872 -1.039876)
			(end -1.769872 -1.039876)
			(stroke
				(width 0.1)
				(type default)
			)
			(layer "F.Fab")
		)
		(fp_line
			(start 1.769872 1.039876)
			(end 1.769872 -1.039876)
			(stroke
				(width 0.1)
				(type default)
			)
			(layer "F.Fab")
		)
		(fp_poly
			(pts
				(xy -1.769872 -1.039876) (xy -0.999998 -1.039876) (xy -0.999998 -1.801876) (xy -2.531872 -1.801876)
				(xy -2.531872 -0.249936) (xy -1.769872 -0.249936)
			)
			(stroke
				(width 0)
				(type default)
			)
			(fill yes)
			(layer "F.Fab")
		)
		(pad "A1" smd circle
			(at -1.500124 -0.750062)
			(size 0.2286 0.2286)
			(layers "F.Cu" "F.Mask" "F.Paste")
			(net "P12V_OCP_SENSE_2")
		)
		(pad "A2" smd circle
			(at -0.999998 -0.750062)
			(size 0.2286 0.2286)
			(layers "F.Cu" "F.Mask" "F.Paste")
			(net "P12V_OCP_VCC_2")
		)
		(pad "A3" smd circle
			(at -0.499872 -0.750062)
			(size 0.2286 0.2286)
			(layers "F.Cu" "F.Mask" "F.Paste")
			(net "P12V_AUX")
		)
		(pad "A4" smd circle
			(at 0 -0.750062)
			(size 0.2286 0.2286)
			(layers "F.Cu" "F.Mask" "F.Paste")
			(net "P12V_OCP_V3_2")
		)
		(pad "A5" smd circle
			(at 0.499872 -0.750062)
			(size 0.2286 0.2286)
			(layers "F.Cu" "F.Mask" "F.Paste")
			(net "P12V_AUX")
		)
		(pad "A6" smd circle
			(at 0.999998 -0.750062)
			(size 0.2286 0.2286)
			(layers "F.Cu" "F.Mask" "F.Paste")
			(net "P12V_OCP_GATE_2")
		)
		(pad "A7" smd circle
			(at 1.500124 -0.750062)
			(size 0.2286 0.2286)
			(layers "F.Cu" "F.Mask" "F.Paste")
			(net "GND")
		)
		(pad "B1" smd circle
			(at -1.500124 -0.249936)
			(size 0.2286 0.2286)
			(layers "F.Cu" "F.Mask" "F.Paste")
			(net "P12V_OCP_CB_2")
		)
		(pad "B2" smd circle
			(at -0.999998 -0.249936)
			(size 0.2286 0.2286)
			(layers "F.Cu" "F.Mask" "F.Paste")
			(net "GND")
		)
		(pad "B3" smd circle
			(at -0.499872 -0.249936)
			(size 0.2286 0.2286)
			(layers "F.Cu" "F.Mask" "F.Paste")
			(net "P12V_AUX")
		)
		(pad "B4" smd circle
			(at 0 -0.249936)
			(size 0.2286 0.2286)
			(layers "F.Cu" "F.Mask" "F.Paste")
			(net "P12V_OCP_V3_2")
		)
		(pad "B5" smd circle
			(at 0.499872 -0.249936)
			(size 0.2286 0.2286)
			(layers "F.Cu" "F.Mask" "F.Paste")
			(net "P12V_AUX")
		)
		(pad "B6" smd circle
			(at 0.999998 -0.249936)
			(size 0.2286 0.2286)
			(layers "F.Cu" "F.Mask" "F.Paste")
			(net "P12V_OCP_V3_2")
		)
		(pad "B7" smd circle
			(at 1.500124 -0.249936)
			(size 0.2286 0.2286)
			(layers "F.Cu" "F.Mask" "F.Paste")
			(net "GND")
		)
		(pad "C1" smd circle
			(at -1.500124 0.249936)
			(size 0.2286 0.2286)
			(layers "F.Cu" "F.Mask" "F.Paste")
			(net "GND")
		)
		(pad "C2" smd circle
			(at -0.999998 0.249936)
			(size 0.2286 0.2286)
			(layers "F.Cu" "F.Mask" "F.Paste")
			(net "GND")
		)
		(pad "C3" smd circle
			(at -0.499872 0.249936)
			(size 0.2286 0.2286)
			(layers "F.Cu" "F.Mask" "F.Paste")
			(net "P12V_AUX")
		)
		(pad "C4" smd circle
			(at 0 0.249936)
			(size 0.2286 0.2286)
			(layers "F.Cu" "F.Mask" "F.Paste")
			(net "P12V_OCP_V3_2")
		)
		(pad "C5" smd circle
			(at 0.499872 0.249936)
			(size 0.2286 0.2286)
			(layers "F.Cu" "F.Mask" "F.Paste")
			(net "P12V_AUX")
		)
		(pad "C6" smd circle
			(at 0.999998 0.249936)
			(size 0.2286 0.2286)
			(layers "F.Cu" "F.Mask" "F.Paste")
			(net "P12V_OCP_V3_2")
		)
		(pad "C7" smd circle
			(at 1.500124 0.249936)
			(size 0.2286 0.2286)
			(layers "F.Cu" "F.Mask" "F.Paste")
			(net "P12V_OCP_FAULT_2")
		)
		(pad "D1" smd circle
			(at -1.500124 0.750062)
			(size 0.2286 0.2286)
			(layers "F.Cu" "F.Mask" "F.Paste")
			(net "P12V_OCP_REG_2")
		)
		(pad "D2" smd circle
			(at -0.999998 0.750062)
			(size 0.2286 0.2286)
			(layers "F.Cu" "F.Mask" "F.Paste")
			(net "P12V_OCP_UV_2")
		)
		(pad "D3" smd circle
			(at -0.499872 0.750062)
			(size 0.2286 0.2286)
			(layers "F.Cu" "F.Mask" "F.Paste")
			(net "P12V_OCP_OV_2")
		)
		(pad "D4" smd circle
			(at 0 0.750062)
			(size 0.2286 0.2286)
			(layers "F.Cu" "F.Mask" "F.Paste")
			(net "P12V_OCP_V3_2")
		)
		(pad "D5" smd circle
			(at 0.499872 0.750062)
			(size 0.2286 0.2286)
			(layers "F.Cu" "F.Mask" "F.Paste")
			(net "P12V_AUX")
		)
		(pad "D6" smd circle
			(at 0.999998 0.750062)
			(size 0.2286 0.2286)
			(layers "F.Cu" "F.Mask" "F.Paste")
			(net "P12V_OCP_V3_2")
		)
		(pad "D7" smd circle
			(at 1.500124 0.750062)
			(size 0.2286 0.2286)
			(layers "F.Cu" "F.Mask" "F.Paste")
			(net "P12V_OCP_PWRGD_2")
		)
	)
)
